FILE_TYPE = CONNECTIVITY;
{Allegro Design Entry HDL 17.4-2019 S026 (4007227) 1/17/2022}
"PAGE_NUMBER" = 99;
0"NC";
1"GND\g";
2"GND\g";
3"P3V3\g";
4"M_C_CPU1_SB_DQS_DP<9:0>";
5"M_C_CPU1_SB_DQS_DN<9:0>";
6"M_C_CPU1_SA_DQS_DP<9:0>";
7"M_C_CPU1_SA_DQS_DN<9:0>";
8"M_C_CPU1_SB_DQ<31:0>";
9"M_C_CPU1_SA_DQ<31:0>";
10"M_C_CPU1_SB_CB<7:0>";
11"M_C_CPU1_SA_CB<7:0>";
12"M_C_CPU1_SB_CA<6:0>";
13"M_C_CPU1_SA_CA<6:0>";
14"M_C_CPU1_SA_DQ<31>";
15"M_C_CPU1_SA_CB<7>";
16"M_C_CPU1_SA_CB<4>";
17"M_C_CPU1_SA_CB<1>";
18"M_C_CPU1_SB_CB<7>";
19"M_C_CPU1_SA_CA<0>";
20"M_C_CPU1_SB_CA<0>";
21"M_C_CPU1_SA_CA<1>";
22"M_C_CPU1_SB_CA<1>";
23"M_C_CPU1_SA_CA<2>";
24"M_C_CPU1_SB_CA<2>";
25"M_C_CPU1_SA_CA<3>";
26"M_C_CPU1_SB_CA<3>";
27"M_C_CPU1_SA_CA<4>";
28"M_C_CPU1_SB_CA<4>";
29"M_C_CPU1_SA_CA<5>";
30"M_C_CPU1_SB_CA<5>";
31"M_C_CPU1_SA_CA<6>";
32"M_C_CPU1_SB_CA<6>";
33"M_C_CPU1_SA_CB<6>";
34"M_C_CPU1_SA_CB<5>";
35"M_C_CPU1_SA_CB<3>";
36"M_C_CPU1_SA_CB<2>";
37"M_C_CPU1_SA_CB<0>";
38"M_C_CPU1_SB_CB<6>";
39"M_C_CPU1_SB_CB<5>";
40"M_C_CPU1_SB_CB<4>";
41"M_C_CPU1_SB_CB<3>";
42"M_C_CPU1_SB_CB<2>";
43"M_C_CPU1_SB_CB<1>";
44"M_C_CPU1_SB_CB<0>";
45"M_C_CPU1_CLK_DP<0>";
46"M_C_CPU1_SB_CS_N<0>";
47"M_C_CPU1_SA_CS_N<1>";
48"M_C_CPU1_SB_CS_N<1>";
49"M_C_CPU1_SA_DQ<30>";
50"M_C_CPU1_SA_DQ<29>";
51"M_C_CPU1_SA_DQ<28>";
52"M_C_CPU1_SA_DQ<27>";
53"M_C_CPU1_SA_DQ<26>";
54"M_C_CPU1_SA_DQ<25>";
55"M_C_CPU1_SA_DQ<24>";
56"M_C_CPU1_SA_DQ<23>";
57"M_C_CPU1_SA_DQ<22>";
58"M_C_CPU1_SA_DQ<21>";
59"M_C_CPU1_SA_DQ<20>";
60"M_C_CPU1_SA_DQ<19>";
61"M_C_CPU1_SA_DQ<18>";
62"M_C_CPU1_SA_DQ<17>";
63"M_C_CPU1_SA_DQ<16>";
64"M_C_CPU1_SA_DQ<15>";
65"M_C_CPU1_SA_DQ<14>";
66"M_C_CPU1_SA_DQ<13>";
67"M_C_CPU1_SA_DQ<12>";
68"M_C_CPU1_SA_DQ<11>";
69"M_C_CPU1_SA_DQ<10>";
70"M_C_CPU1_SA_DQ<9>";
71"M_C_CPU1_SA_DQ<8>";
72"M_C_CPU1_SA_DQ<7>";
73"M_C_CPU1_SA_DQ<6>";
74"M_C_CPU1_SA_DQ<5>";
75"M_C_CPU1_SA_DQ<4>";
76"M_C_CPU1_SA_DQ<3>";
77"M_C_CPU1_SA_DQ<2>";
78"M_C_CPU1_SA_DQ<1>";
79"M_C_CPU1_SA_DQ<0>";
80"M_C_CPU1_SB_DQ<31>";
81"M_C_CPU1_SB_DQ<30>";
82"M_C_CPU1_SB_DQ<29>";
83"M_C_CPU1_SB_DQ<28>";
84"M_C_CPU1_SB_DQ<27>";
85"M_C_CPU1_SB_DQ<26>";
86"M_C_CPU1_SB_DQ<25>";
87"M_C_CPU1_SB_DQ<24>";
88"M_C_CPU1_SB_DQ<23>";
89"M_C_CPU1_SB_DQ<22>";
90"M_C_CPU1_SB_DQ<21>";
91"M_C_CPU1_SB_DQ<20>";
92"M_C_CPU1_SB_DQ<19>";
93"M_C_CPU1_SB_DQ<18>";
94"M_C_CPU1_SB_DQ<17>";
95"M_C_CPU1_SB_DQ<16>";
96"M_C_CPU1_SB_DQ<15>";
97"M_C_CPU1_SB_DQ<14>";
98"M_C_CPU1_SB_DQ<13>";
99"M_C_CPU1_SB_DQ<12>";
100"M_C_CPU1_SB_DQ<11>";
101"M_C_CPU1_SB_DQ<10>";
102"M_C_CPU1_SB_DQ<9>";
103"M_C_CPU1_SB_DQ<8>";
104"M_C_CPU1_SB_DQ<7>";
105"M_C_CPU1_SB_DQ<6>";
106"M_C_CPU1_SB_DQ<5>";
107"M_C_CPU1_SB_DQ<4>";
108"M_C_CPU1_SB_DQ<3>";
109"M_C_CPU1_SB_DQ<2>";
110"M_C_CPU1_SB_DQ<1>";
111"M_C_CPU1_SB_DQ<0>";
112"M_C_CPU1_SA_RSP<0>";
113"M_C_CPU1_SB_RSP<0>";
114"M_C_CPU1_SA_PAR";
115"M_C_CPU1_SA_DQS_DN<7>";
116"M_C_CPU1_SA_DQS_DP<6>";
117"M_C_CPU1_SB_DQS_DP<8>";
118"M_C_CPU1_SB_DQS_DN<8>";
119"M_C_CPU1_SB_DQS_DP<7>";
120"M_C_CPU1_SA_DQS_DN<0>";
121"M_C_CPU1_SA_DQS_DP<0>";
122"M_C_CPU1_SB_DQS_DN<0>";
123"M_C_CPU1_SB_DQS_DP<0>";
124"M_C_CPU1_SA_DQS_DN<1>";
125"M_C_CPU1_SA_DQS_DP<1>";
126"M_C_CPU1_SB_DQS_DN<1>";
127"M_C_CPU1_SB_DQS_DP<1>";
128"M_C_CPU1_SA_DQS_DN<2>";
129"M_C_CPU1_SA_DQS_DP<2>";
130"M_C_CPU1_SB_DQS_DN<2>";
131"M_C_CPU1_SB_DQS_DP<2>";
132"M_C_CPU1_SA_DQS_DN<3>";
133"M_C_CPU1_SA_DQS_DP<3>";
134"M_C_CPU1_SB_DQS_DN<3>";
135"M_C_CPU1_SB_DQS_DP<3>";
136"M_C_CPU1_SA_DQS_DN<4>";
137"M_C_CPU1_SA_DQS_DP<4>";
138"M_C_CPU1_SB_DQS_DN<4>";
139"M_C_CPU1_SB_DQS_DP<4>";
140"M_C_CPU1_SA_DQS_DN<5>";
141"M_C_CPU1_SA_DQS_DP<5>";
142"M_C_CPU1_SB_DQS_DN<5>";
143"M_C_CPU1_SB_DQS_DP<5>";
144"M_C_CPU1_SA_DQS_DN<6>";
145"M_C_CPU1_SB_DQS_DN<6>";
146"M_C_CPU1_SB_DQS_DP<6>";
147"M_C_CPU1_SA_DQS_DP<7>";
148"M_C_CPU1_SB_DQS_DN<7>";
149"M_C_CPU1_SA_DQS_DN<8>";
150"M_C_CPU1_SA_DQS_DP<8>";
151"M_C_CPU1_SA_DQS_DN<9>";
152"M_C_CPU1_SA_DQS_DP<9>";
153"M_C_CPU1_SB_DQS_DN<9>";
154"M_C_CPU1_SB_DQS_DP<9>";
155"M_C_CPU1_CLK_DN<0>";
156"PD_CHC_CPU1_DIMM_SAA";
157"PWRGD_CHAF_CPU1";
158"M_C_CPU1_SB_PAR";
159"M_C_CPU1_SA_CS_N<0>";
160"M_C_CPU1_RESET_N";
161"P12V_MEM_CPU1\g";
162"GND\g";
163"GND\g";
164"GND\g";
165"PWRGD_CHC_CPU1_DIMM";
166"M_C_CPU1_ALERT_N";
167"I3C_SPD_DDRAF_CPU1_SCL";
168"I3C_SPD_DDRAF_CPU1_SDA";
169"P3V3_AUX\g";
170"I3C_SPD_DDRC_CPU1_SDA";
171"I3C_SPD_DDRC_CPU1_SCL";
172"PD_CHC_CPU1_DIMM_SAA";
%"TAP"
"1","(-6200,4000)","0","mstr_standard","I100";
;
CDS_LIB"mstr_standard"
BODY_TYPE"PLUMBING"
HDL_TAP"TRUE";
"B \NAC \NWC"9;
"S \NAC"
BN"3"76;
%"TAP"
"1","(-6200,4050)","0","mstr_standard","I101";
;
CDS_LIB"mstr_standard"
BODY_TYPE"PLUMBING"
HDL_TAP"TRUE";
"B \NAC \NWC"9;
"S \NAC"
BN"4"75;
%"TAP"
"1","(-6200,4100)","0","mstr_standard","I102";
;
CDS_LIB"mstr_standard"
BODY_TYPE"PLUMBING"
HDL_TAP"TRUE";
"B \NAC \NWC"9;
"S \NAC"
BN"5"74;
%"TAP"
"1","(-6200,4150)","0","mstr_standard","I103";
;
CDS_LIB"mstr_standard"
BODY_TYPE"PLUMBING"
HDL_TAP"TRUE";
"B \NAC \NWC"9;
"S \NAC"
BN"6"73;
%"TAP"
"1","(-6200,4200)","0","mstr_standard","I104";
;
CDS_LIB"mstr_standard"
BODY_TYPE"PLUMBING"
HDL_TAP"TRUE";
"B \NAC \NWC"9;
"S \NAC"
BN"7"72;
%"TAP"
"1","(-6200,4300)","0","mstr_standard","I105";
;
CDS_LIB"mstr_standard"
BODY_TYPE"PLUMBING"
HDL_TAP"TRUE";
"B \NAC \NWC"9;
"S \NAC"
BN"9"70;
%"TAP"
"1","(-6200,4350)","0","mstr_standard","I106";
;
CDS_LIB"mstr_standard"
BODY_TYPE"PLUMBING"
HDL_TAP"TRUE";
"B \NAC \NWC"9;
"S \NAC"
BN"10"69;
%"TAP"
"1","(-6200,4250)","0","mstr_standard","I107";
;
CDS_LIB"mstr_standard"
BODY_TYPE"PLUMBING"
HDL_TAP"TRUE";
"B \NAC \NWC"9;
"S \NAC"
BN"8"71;
%"TAP"
"1","(-6200,4400)","0","mstr_standard","I108";
;
CDS_LIB"mstr_standard"
BODY_TYPE"PLUMBING"
HDL_TAP"TRUE";
"B \NAC \NWC"9;
"S \NAC"
BN"11"68;
%"TAP"
"1","(-6200,4450)","0","mstr_standard","I109";
;
CDS_LIB"mstr_standard"
BODY_TYPE"PLUMBING"
HDL_TAP"TRUE";
"B \NAC \NWC"9;
"S \NAC"
BN"12"67;
%"TAP"
"1","(-6200,4550)","0","mstr_standard","I110";
;
CDS_LIB"mstr_standard"
BODY_TYPE"PLUMBING"
HDL_TAP"TRUE";
"B \NAC \NWC"9;
"S \NAC"
BN"14"65;
%"TAP"
"1","(-6200,4600)","0","mstr_standard","I111";
;
CDS_LIB"mstr_standard"
BODY_TYPE"PLUMBING"
HDL_TAP"TRUE";
"B \NAC \NWC"9;
"S \NAC"
BN"15"64;
%"TAP"
"1","(-6200,4500)","0","mstr_standard","I112";
;
CDS_LIB"mstr_standard"
BODY_TYPE"PLUMBING"
HDL_TAP"TRUE";
"B \NAC \NWC"9;
"S \NAC"
BN"13"66;
%"TAP"
"1","(-6200,4650)","0","mstr_standard","I113";
;
CDS_LIB"mstr_standard"
BODY_TYPE"PLUMBING"
HDL_TAP"TRUE";
"B \NAC \NWC"9;
"S \NAC"
BN"16"63;
%"TAP"
"1","(-6200,4700)","0","mstr_standard","I114";
;
CDS_LIB"mstr_standard"
BODY_TYPE"PLUMBING"
HDL_TAP"TRUE";
"B \NAC \NWC"9;
"S \NAC"
BN"17"62;
%"TAP"
"1","(-6200,4850)","0","mstr_standard","I115";
;
CDS_LIB"mstr_standard"
BODY_TYPE"PLUMBING"
HDL_TAP"TRUE";
"B \NAC \NWC"9;
"S \NAC"
BN"20"59;
%"TAP"
"1","(-6200,4800)","0","mstr_standard","I116";
;
CDS_LIB"mstr_standard"
BODY_TYPE"PLUMBING"
HDL_TAP"TRUE";
"B \NAC \NWC"9;
"S \NAC"
BN"19"60;
%"TAP"
"1","(-6200,4750)","0","mstr_standard","I117";
;
CDS_LIB"mstr_standard"
BODY_TYPE"PLUMBING"
HDL_TAP"TRUE";
"B \NAC \NWC"9;
"S \NAC"
BN"18"61;
%"TAP"
"1","(-6200,4900)","0","mstr_standard","I118";
;
CDS_LIB"mstr_standard"
BODY_TYPE"PLUMBING"
HDL_TAP"TRUE";
"B \NAC \NWC"9;
"S \NAC"
BN"21"58;
%"TAP"
"1","(-6200,4950)","0","mstr_standard","I119";
;
CDS_LIB"mstr_standard"
BODY_TYPE"PLUMBING"
HDL_TAP"TRUE";
"B \NAC \NWC"9;
"S \NAC"
BN"22"57;
%"TAP"
"1","(-6200,5000)","0","mstr_standard","I120";
;
CDS_LIB"mstr_standard"
BODY_TYPE"PLUMBING"
HDL_TAP"TRUE";
"B \NAC \NWC"9;
"S \NAC"
BN"23"56;
%"TAP"
"1","(-6200,5050)","0","mstr_standard","I121";
;
CDS_LIB"mstr_standard"
BODY_TYPE"PLUMBING"
HDL_TAP"TRUE";
"B \NAC \NWC"9;
"S \NAC"
BN"24"55;
%"TAP"
"1","(-6200,5100)","0","mstr_standard","I122";
;
CDS_LIB"mstr_standard"
BODY_TYPE"PLUMBING"
HDL_TAP"TRUE";
"B \NAC \NWC"9;
"S \NAC"
BN"25"54;
%"TAP"
"1","(-6200,5250)","0","mstr_standard","I123";
;
CDS_LIB"mstr_standard"
BODY_TYPE"PLUMBING"
HDL_TAP"TRUE";
"B \NAC \NWC"9;
"S \NAC"
BN"28"51;
%"TAP"
"1","(-6200,5200)","0","mstr_standard","I124";
;
CDS_LIB"mstr_standard"
BODY_TYPE"PLUMBING"
HDL_TAP"TRUE";
"B \NAC \NWC"9;
"S \NAC"
BN"27"52;
%"TAP"
"1","(-6200,5150)","0","mstr_standard","I125";
;
CDS_LIB"mstr_standard"
BODY_TYPE"PLUMBING"
HDL_TAP"TRUE";
"B \NAC \NWC"9;
"S \NAC"
BN"26"53;
%"TAP"
"1","(-6200,5300)","0","mstr_standard","I126";
;
CDS_LIB"mstr_standard"
BODY_TYPE"PLUMBING"
HDL_TAP"TRUE";
"B \NAC \NWC"9;
"S \NAC"
BN"29"50;
%"TAP"
"1","(-6200,5350)","0","mstr_standard","I127";
;
CDS_LIB"mstr_standard"
BODY_TYPE"PLUMBING"
HDL_TAP"TRUE";
"B \NAC \NWC"9;
"S \NAC"
BN"30"49;
%"TAP"
"1","(-6200,5400)","0","mstr_standard","I128";
;
CDS_LIB"mstr_standard"
BODY_TYPE"PLUMBING"
HDL_TAP"TRUE";
"B \NAC \NWC"9;
"S \NAC"
BN"31"14;
%"GND"
"1","(-6600,1025)","0","mstr_symbols","I147";
;
SIZE"1B"
BOM_COST"MEM"
CDS_LIB"mstr_symbols"
VOLTAGE"0.0"
BODY_TYPE"PLUMBING"
HDL_POWER"GND";
"A\NAC"1;
%"Q_RES"
"2","(-6600,1250)","0","pure_quanta","I148";
;
LOCATION"R771"
$SEC"1"
CDS_SEC"1"
PACK_TYPE"0402LF"
VALUE"23.2K"
TOLERANCE"1%"
MATERIAL"CHIP"
WATTAGE"1/16W"
CDS_LIB"pure_quanta"
PART_NUMBER"CS32322FB03";
"A"
$PN"1"156;
"B"
$PN"2"1;
%"GND"
"1","(-2225,2000)","0","mstr_symbols","I154";
;
SIZE"1B"
CDS_LIB"mstr_symbols"
VOLTAGE"0.0"
BODY_TYPE"PLUMBING"
HDL_POWER"GND";
"A\NAC"164;
%"SCONN288_DDR506112002KQ"
"3","(-1325,3750)","0","pure_quanta","I155";
;
LOCATION"J28"
$SEC"3"
CDS_SEC"3"
MATERIAL"IO"
PART_TYPE"SMLF"
VALUE"SCONN288_DDR506112002KQ"
CDS_LMAN_SYM_OUTLINE"-450,1800,450,-1750"
NEEDS_NO_SIZE"TRUE"
CDS_LIB"pure_quanta"
PART_NUMBER"DFHST8FS479";
"G3"
$PN"G3"163;
"G2"
$PN"G2"163;
"G1"
$PN"G1"163;
"VSS62"
$PN"141"163;
"VSS61"
$PN"139"163;
"VSS60"
$PN"136"163;
"VSS58"
$PN"132"163;
"VSS104"
$PN"240"164;
"VSS102"
$PN"235"164;
"VSS100"
$PN"230"164;
"VIN_BULK2"
$PN"146"161;
"VIN_BULK1"
$PN"145"161;
"VIN_BULK0"
$PN"1"161;
"VSS126"
$PN"288"164;
"VSS125"
$PN"286"164;
"VSS124"
$PN"284"164;
"VSS123"
$PN"281"164;
"VSS122"
$PN"279"164;
"VSS121"
$PN"277"164;
"VSS120"
$PN"275"164;
"VSS119"
$PN"273"164;
"VSS118"
$PN"270"164;
"VSS117"
$PN"268"164;
"VSS116"
$PN"266"164;
"VSS115"
$PN"264"164;
"VSS114"
$PN"262"164;
"VSS113"
$PN"259"164;
"VSS112"
$PN"257"164;
"VSS111"
$PN"255"164;
"VSS110"
$PN"253"164;
"VSS109"
$PN"251"164;
"VSS108"
$PN"248"164;
"VSS107"
$PN"246"164;
"VSS106"
$PN"244"164;
"VSS105"
$PN"242"164;
"VSS103"
$PN"237"164;
"VSS101"
$PN"233"164;
"VSS99"
$PN"228"164;
"VSS98"
$PN"226"164;
"VSS97"
$PN"224"164;
"VSS96"
$PN"222"164;
"VSS95"
$PN"219"164;
"VSS94"
$PN"216"164;
"VSS93"
$PN"214"164;
"VSS92"
$PN"212"164;
"VSS91"
$PN"210"164;
"VSS90"
$PN"208"164;
"VSS89"
$PN"206"164;
"VSS88"
$PN"204"164;
"VSS87"
$PN"202"164;
"VSS86"
$PN"199"164;
"VSS85"
$PN"197"164;
"VSS84"
$PN"195"164;
"VSS83"
$PN"193"164;
"VSS82"
$PN"191"164;
"VSS81"
$PN"188"164;
"VSS80"
$PN"186"164;
"VSS79"
$PN"184"164;
"VSS78"
$PN"182"164;
"VSS77"
$PN"180"164;
"VSS76"
$PN"177"164;
"VSS75"
$PN"175"164;
"VSS74"
$PN"173"164;
"VSS73"
$PN"171"164;
"VSS72"
$PN"169"164;
"VSS71"
$PN"166"164;
"VSS70"
$PN"164"164;
"VSS69"
$PN"162"164;
"VSS68"
$PN"160"164;
"VSS67"
$PN"158"164;
"VSS66"
$PN"155"164;
"VSS65"
$PN"153"164;
"VSS64"
$PN"151"164;
"VSS63"
$PN"143"163;
"VSS59"
$PN"134"163;
"VSS57"
$PN"130"163;
"VSS56"
$PN"128"163;
"VSS55"
$PN"125"163;
"VSS54"
$PN"123"163;
"VSS53"
$PN"121"163;
"VSS52"
$PN"119"163;
"VSS51"
$PN"117"163;
"VSS50"
$PN"114"163;
"VSS49"
$PN"112"163;
"VSS48"
$PN"110"163;
"VSS47"
$PN"108"163;
"VSS46"
$PN"106"163;
"VSS45"
$PN"103"163;
"VSS44"
$PN"101"163;
"VSS43"
$PN"99"163;
"VSS42"
$PN"97"163;
"VSS41"
$PN"95"163;
"VSS40"
$PN"92"163;
"VSS39"
$PN"90"163;
"VSS38"
$PN"88"163;
"VSS37"
$PN"85"163;
"VSS36"
$PN"83"163;
"VSS35"
$PN"81"163;
"VSS34"
$PN"79"163;
"VSS33"
$PN"77"163;
"VSS32"
$PN"75"163;
"VSS31"
$PN"73"163;
"VSS30"
$PN"71"163;
"VSS29"
$PN"69"163;
"VSS28"
$PN"67"163;
"VSS27"
$PN"65"163;
"VSS26"
$PN"63"163;
"VSS25"
$PN"61"163;
"VSS24"
$PN"59"163;
"VSS23"
$PN"57"163;
"VSS22"
$PN"54"163;
"VSS21"
$PN"52"163;
"VSS20"
$PN"50"163;
"VSS19"
$PN"48"163;
"VSS18"
$PN"46"163;
"VSS17"
$PN"43"163;
"VSS16"
$PN"41"163;
"VSS15"
$PN"39"163;
"VSS14"
$PN"37"163;
"VSS13"
$PN"35"163;
"VSS12"
$PN"32"163;
"VSS11"
$PN"30"163;
"VSS10"
$PN"28"163;
"VSS9"
$PN"26"163;
"VSS8"
$PN"24"163;
"VSS7"
$PN"21"163;
"VSS6"
$PN"19"163;
"VSS5"
$PN"17"163;
"VSS4"
$PN"15"163;
"VSS3"
$PN"13"163;
"VSS2"
$PN"10"163;
"VSS1"
$PN"8"163;
"VSS0"
$PN"6"163;
%"GND"
"1","(-425,1800)","0","mstr_symbols","I156";
;
SIZE"1B"
CDS_LIB"mstr_symbols"
VOLTAGE"0.0"
BODY_TYPE"PLUMBING"
HDL_POWER"GND";
"A\NAC"163;
%"Q_CAP"
"1","(-8775,3225)","2","pure_quanta","I185";
;
LOCATION"C144"
$SEC"1"
CDS_SEC"1"
MATERIAL"X7R"
PACK_TYPE"0402"
TOLERANCE"10%"
VALUE"0.1UF"
VOLTAGE"25V"
CDS_LIB"pure_quanta"
BOM_COST"MEM"
ROOM""
PART_NUMBER"CH4104K1B00";
"B"
$PN"2"2;
"A"
$PN"1"169;
%"GND"
"1","(-8775,3000)","0","mstr_symbols","I186";
;
BOM_COST"MEM"
SIZE"1B"
CDS_LIB"mstr_symbols"
VOLTAGE"0"
ROOM"MEM_EFGH_DECOUPLING_CAPS"
BODY_TYPE"PLUMBING"
HDL_POWER"GND";
"A\NAC"2;
%"Q_RES"
"1","(-8700,2150)","2","pure_quanta","I188";
;
LOCATION"R305"
$SEC"1"
CDS_SEC"1"
VALUE"1K"
TOLERANCE"1%"
BOM_COST"MEM"
CDS_LIB"pure_quanta"
WATTAGE"1/16W"
MATERIAL"CHIP"
PACK_TYPE"0402LF"
ROOM""
PART_NUMBER"CS21002FB06";
"B"
$PN"2"157;
"A"
$PN"1"165;
%"VCC_CORE"
"1","(-8575,2475)","0","mstr_symbols","I189";
;
HDL_POWER"P3V3"
CDS_LIB"mstr_symbols"
VOLTAGE"3.3"
ROOM"PVCCINFAON_CPU0_CTRL";
"A"3;
%"Q_RES"
"2","(-8575,2300)","0","pure_quanta","I190";
;
LOCATION"R105"
$SEC"1"
CDS_SEC"1"
TOLERANCE"1%"
MATERIAL"EMPTY"
PACK_TYPE"0402LF"
WATTAGE"1/16W"
VALUE"1K"
CDS_LIB"pure_quanta"
BOM_COST"MEM"
ROOM""
PART_NUMBER"CS21002FB06";
"A"
$PN"1"3;
"B"
$PN"2"165;
%"TAP"
"1","(-3550,3750)","0","mstr_standard","I191";
;
CDS_LIB"mstr_standard"
BODY_TYPE"PLUMBING"
HDL_TAP"TRUE";
"B \NAC \NWC"6;
"S \NAC"
BN"1"125;
%"TAP"
"1","(-3550,3850)","0","mstr_standard","I193";
;
CDS_LIB"mstr_standard"
BODY_TYPE"PLUMBING"
HDL_TAP"TRUE";
"B \NAC \NWC"6;
"S \NAC"
BN"2"129;
%"TAP"
"1","(-3350,4400)","0","mstr_standard","I196";
;
CDS_LIB"mstr_standard"
BODY_TYPE"PLUMBING"
HDL_TAP"TRUE";
"B \NAC \NWC"7;
"S \NAC"
BN"8"149;
%"TAP"
"1","(-3350,4500)","0","mstr_standard","I197";
;
CDS_LIB"mstr_standard"
BODY_TYPE"PLUMBING"
HDL_TAP"TRUE";
"B \NAC \NWC"7;
"S \NAC"
BN"9"151;
%"TAP"
"1","(-3550,4450)","0","mstr_standard","I198";
;
CDS_LIB"mstr_standard"
BODY_TYPE"PLUMBING"
HDL_TAP"TRUE";
"B \NAC \NWC"6;
"S \NAC"
BN"8"150;
%"TAP"
"1","(-3550,4550)","0","mstr_standard","I199";
;
CDS_LIB"mstr_standard"
BODY_TYPE"PLUMBING"
HDL_TAP"TRUE";
"B \NAC \NWC"6;
"S \NAC"
BN"9"152;
%"TAP"
"1","(-3550,4350)","0","mstr_standard","I200";
;
CDS_LIB"mstr_standard"
BODY_TYPE"PLUMBING"
HDL_TAP"TRUE";
"B \NAC \NWC"6;
"S \NAC"
BN"7"147;
%"TAP"
"1","(-3350,4100)","0","mstr_standard","I203";
;
CDS_LIB"mstr_standard"
BODY_TYPE"PLUMBING"
HDL_TAP"TRUE";
"B \NAC \NWC"7;
"S \NAC"
BN"5"140;
%"TAP"
"1","(-3350,4300)","0","mstr_standard","I204";
;
CDS_LIB"mstr_standard"
BODY_TYPE"PLUMBING"
HDL_TAP"TRUE";
"B \NAC \NWC"7;
"S \NAC"
BN"7"115;
%"TAP"
"1","(-3350,4200)","0","mstr_standard","I205";
;
CDS_LIB"mstr_standard"
BODY_TYPE"PLUMBING"
HDL_TAP"TRUE";
"B \NAC \NWC"7;
"S \NAC"
BN"6"144;
%"TAP"
"1","(-3550,4250)","0","mstr_standard","I206";
;
CDS_LIB"mstr_standard"
BODY_TYPE"PLUMBING"
HDL_TAP"TRUE";
"B \NAC \NWC"6;
"S \NAC"
BN"6"116;
%"TAP"
"1","(-3550,4150)","0","mstr_standard","I207";
;
CDS_LIB"mstr_standard"
BODY_TYPE"PLUMBING"
HDL_TAP"TRUE";
"B \NAC \NWC"6;
"S \NAC"
BN"5"141;
%"TAP"
"1","(-3350,3900)","0","mstr_standard","I208";
;
CDS_LIB"mstr_standard"
BODY_TYPE"PLUMBING"
HDL_TAP"TRUE";
"B \NAC \NWC"7;
"S \NAC"
BN"3"132;
%"TAP"
"1","(-3350,4000)","0","mstr_standard","I209";
;
CDS_LIB"mstr_standard"
BODY_TYPE"PLUMBING"
HDL_TAP"TRUE";
"B \NAC \NWC"7;
"S \NAC"
BN"4"136;
%"TAP"
"1","(-3550,4050)","0","mstr_standard","I210";
;
CDS_LIB"mstr_standard"
BODY_TYPE"PLUMBING"
HDL_TAP"TRUE";
"B \NAC \NWC"6;
"S \NAC"
BN"4"137;
%"TAP"
"1","(-3550,3950)","0","mstr_standard","I211";
;
CDS_LIB"mstr_standard"
BODY_TYPE"PLUMBING"
HDL_TAP"TRUE";
"B \NAC \NWC"6;
"S \NAC"
BN"3"133;
%"TAP"
"1","(-3350,3600)","0","mstr_standard","I212";
;
CDS_LIB"mstr_standard"
BODY_TYPE"PLUMBING"
HDL_TAP"TRUE";
"B \NAC \NWC"7;
"S \NAC"
BN"0"120;
%"TAP"
"1","(-3350,3800)","0","mstr_standard","I213";
;
CDS_LIB"mstr_standard"
BODY_TYPE"PLUMBING"
HDL_TAP"TRUE";
"B \NAC \NWC"7;
"S \NAC"
BN"2"128;
%"TAP"
"1","(-3350,3700)","0","mstr_standard","I214";
;
CDS_LIB"mstr_standard"
BODY_TYPE"PLUMBING"
HDL_TAP"TRUE";
"B \NAC \NWC"7;
"S \NAC"
BN"1"124;
%"TAP"
"1","(-3550,3650)","0","mstr_standard","I215";
;
CDS_LIB"mstr_standard"
BODY_TYPE"PLUMBING"
HDL_TAP"TRUE";
"B \NAC \NWC"6;
"S \NAC"
BN"0"121;
%"TAP"
"1","(-3350,3350)","0","mstr_standard","I216";
;
CDS_LIB"mstr_standard"
BODY_TYPE"PLUMBING"
HDL_TAP"TRUE";
"B \NAC \NWC"5;
"S \NAC"
BN"8"118;
%"TAP"
"1","(-3350,3450)","0","mstr_standard","I217";
;
CDS_LIB"mstr_standard"
BODY_TYPE"PLUMBING"
HDL_TAP"TRUE";
"B \NAC \NWC"5;
"S \NAC"
BN"9"153;
%"TAP"
"1","(-3550,3500)","0","mstr_standard","I218";
;
CDS_LIB"mstr_standard"
BODY_TYPE"PLUMBING"
HDL_TAP"TRUE";
"B \NAC \NWC"4;
"S \NAC"
BN"9"154;
%"TAP"
"1","(-3550,3400)","0","mstr_standard","I219";
;
CDS_LIB"mstr_standard"
BODY_TYPE"PLUMBING"
HDL_TAP"TRUE";
"B \NAC \NWC"4;
"S \NAC"
BN"8"117;
%"SCONN288_DDR506112002KQ"
"1","(-7050,3650)","0","pure_quanta","I22";
;
LOCATION"J28"
$SEC"1"
CDS_SEC"1"
PART_TYPE"SMLF"
VALUE"SCONN288_DDR506112002KQ"
MATERIAL"IO"
CDS_LMAN_SYM_OUTLINE"-450,1900,450,-1850"
NEEDS_NO_SIZE"TRUE"
CDS_LIB"pure_quanta"
PART_NUMBER"DFHST8FS479";
"PWR_GOOD||FAIL_N"
$PN"147"165;
"DQ31_A"
$PN"194"14;
"CB7_A"
$PN"205"15;
"CB4_A"
$PN"58"16;
"CB1_A"
$PN"53"17;
"CB7_B"
$PN"236"18;
"ALERT_N \B"
$PN"62"166;
"CA0_A"
$PN"66"19;
"CA0_B"
$PN"76"20;
"CA1_A"
$PN"211"21;
"CA1_B"
$PN"221"22;
"CA2_A"
$PN"68"23;
"CA2_B"
$PN"78"24;
"CA3_A"
$PN"213"25;
"CA3_B"
$PN"223"26;
"CA4_A"
$PN"70"27;
"CA4_B"
$PN"80"28;
"CA5_A"
$PN"215"29;
"CA5_B"
$PN"225"30;
"CA6_A"
$PN"72"31;
"CA6_B"
$PN"82"32;
"CB6_A"
$PN"203"33;
"CB5_A"
$PN"60"34;
"CB3_A"
$PN"198"35;
"CB2_A"
$PN"196"36;
"CB0_A"
$PN"51"37;
"CB6_B"
$PN"234"38;
"CB5_B"
$PN"91"39;
"CB4_B"
$PN"89"40;
"CB3_B"
$PN"243"41;
"CB2_B"
$PN"241"42;
"CB1_B"
$PN"98"43;
"CB0_B"
$PN"96"44;
"CK_C \B"
$PN"218"155;
"CK_T"
$PN"217"45;
"CS0_A_N"
$PN"64"159;
"CS0_B_N"
$PN"84"46;
"CS1_A_N"
$PN"209"47;
"CS1_B_N"
$PN"229"48;
"DQ30_A"
$PN"192"49;
"DQ29_A"
$PN"49"50;
"DQ28_A"
$PN"47"51;
"DQ27_A"
$PN"187"52;
"DQ26_A"
$PN"185"53;
"DQ25_A"
$PN"42"54;
"DQ24_A"
$PN"40"55;
"DQ23_A"
$PN"183"56;
"DQ22_A"
$PN"181"57;
"DQ21_A"
$PN"38"58;
"DQ20_A"
$PN"36"59;
"DQ19_A"
$PN"176"60;
"DQ18_A"
$PN"174"61;
"DQ17_A"
$PN"31"62;
"DQ16_A"
$PN"29"63;
"DQ15_A"
$PN"172"64;
"DQ14_A"
$PN"170"65;
"DQ13_A"
$PN"27"66;
"DQ12_A"
$PN"25"67;
"DQ11_A"
$PN"165"68;
"DQ10_A"
$PN"163"69;
"DQ9_A"
$PN"20"70;
"DQ8_A"
$PN"18"71;
"DQ7_A"
$PN"161"72;
"DQ6_A"
$PN"159"73;
"DQ5_A"
$PN"16"74;
"DQ4_A"
$PN"14"75;
"DQ3_A"
$PN"154"76;
"DQ2_A"
$PN"152"77;
"DQ1_A"
$PN"9"78;
"DQ0_A"
$PN"7"79;
"DQ31_B"
$PN"287"80;
"DQ30_B"
$PN"285"81;
"DQ29_B"
$PN"142"82;
"DQ28_B"
$PN"140"83;
"DQ27_B"
$PN"280"84;
"DQ26_B"
$PN"278"85;
"DQ25_B"
$PN"135"86;
"DQ24_B"
$PN"133"87;
"DQ23_B"
$PN"276"88;
"DQ22_B"
$PN"274"89;
"DQ21_B"
$PN"131"90;
"DQ20_B"
$PN"129"91;
"DQ19_B"
$PN"269"92;
"DQ18_B"
$PN"267"93;
"DQ17_B"
$PN"124"94;
"DQ16_B"
$PN"122"95;
"DQ15_B"
$PN"265"96;
"DQ14_B"
$PN"263"97;
"DQ13_B"
$PN"120"98;
"DQ12_B"
$PN"118"99;
"DQ11_B"
$PN"258"100;
"DQ10_B"
$PN"256"101;
"DQ9_B"
$PN"113"102;
"DQ8_B"
$PN"111"103;
"DQ7_B"
$PN"254"104;
"DQ6_B"
$PN"252"105;
"DQ5_B"
$PN"109"106;
"DQ4_B"
$PN"107"107;
"DQ3_B"
$PN"247"108;
"DQ2_B"
$PN"245"109;
"DQ1_B"
$PN"102"110;
"DQ0_B"
$PN"100"111;
"HAS"
$PN"148"172;
"HSCL"
$PN"4"171;
"HSDA"
$PN"5"170;
"LBD||RSP_A_N"
$PN"86"112;
"LBS||RSP_B_N"
$PN"87"113;
"PAR_A"
$PN"74"114;
"PAR_B"
$PN"227"158;
"RESET_N \B"
$PN"207"160;
"RFU6"
$PN"232"0;
"RFU5"
$PN"231"0;
"RFU4"
$PN"220"0;
"RFU3"
$PN"150"0;
"RFU2"
$PN"149"0;
"RFU1"
$PN"144"0;
"RFU0"
$PN"2"0;
"VIN_MGMT"
$PN"3"169;
%"TAP"
"1","(-3550,3300)","0","mstr_standard","I220";
;
CDS_LIB"mstr_standard"
BODY_TYPE"PLUMBING"
HDL_TAP"TRUE";
"B \NAC \NWC"4;
"S \NAC"
BN"7"119;
%"TAP"
"1","(-3350,3050)","0","mstr_standard","I221";
;
CDS_LIB"mstr_standard"
BODY_TYPE"PLUMBING"
HDL_TAP"TRUE";
"B \NAC \NWC"5;
"S \NAC"
BN"5"142;
%"TAP"
"1","(-3350,3250)","0","mstr_standard","I222";
;
CDS_LIB"mstr_standard"
BODY_TYPE"PLUMBING"
HDL_TAP"TRUE";
"B \NAC \NWC"5;
"S \NAC"
BN"7"148;
%"TAP"
"1","(-3350,3150)","0","mstr_standard","I223";
;
CDS_LIB"mstr_standard"
BODY_TYPE"PLUMBING"
HDL_TAP"TRUE";
"B \NAC \NWC"5;
"S \NAC"
BN"6"145;
%"TAP"
"1","(-3550,3200)","0","mstr_standard","I224";
;
CDS_LIB"mstr_standard"
BODY_TYPE"PLUMBING"
HDL_TAP"TRUE";
"B \NAC \NWC"4;
"S \NAC"
BN"6"146;
%"TAP"
"1","(-3550,3100)","0","mstr_standard","I225";
;
CDS_LIB"mstr_standard"
BODY_TYPE"PLUMBING"
HDL_TAP"TRUE";
"B \NAC \NWC"4;
"S \NAC"
BN"5"143;
%"TAP"
"1","(-3350,2950)","0","mstr_standard","I226";
;
CDS_LIB"mstr_standard"
BODY_TYPE"PLUMBING"
HDL_TAP"TRUE";
"B \NAC \NWC"5;
"S \NAC"
BN"4"138;
%"TAP"
"1","(-3350,2850)","0","mstr_standard","I227";
;
CDS_LIB"mstr_standard"
BODY_TYPE"PLUMBING"
HDL_TAP"TRUE";
"B \NAC \NWC"5;
"S \NAC"
BN"3"134;
%"TAP"
"1","(-3550,3000)","0","mstr_standard","I228";
;
CDS_LIB"mstr_standard"
BODY_TYPE"PLUMBING"
HDL_TAP"TRUE";
"B \NAC \NWC"4;
"S \NAC"
BN"4"139;
%"TAP"
"1","(-3550,2800)","0","mstr_standard","I229";
;
CDS_LIB"mstr_standard"
BODY_TYPE"PLUMBING"
HDL_TAP"TRUE";
"B \NAC \NWC"4;
"S \NAC"
BN"2"131;
%"TAP"
"1","(-7900,3200)","2","mstr_standard","I23";
;
CDS_LIB"mstr_standard"
BODY_TYPE"PLUMBING"
HDL_TAP"TRUE";
"B \NAC \NWC"10;
"S \NAC"
BN"0"44;
%"TAP"
"1","(-3550,2900)","0","mstr_standard","I230";
;
CDS_LIB"mstr_standard"
BODY_TYPE"PLUMBING"
HDL_TAP"TRUE";
"B \NAC \NWC"4;
"S \NAC"
BN"3"135;
%"TAP"
"1","(-3350,2550)","0","mstr_standard","I231";
;
CDS_LIB"mstr_standard"
BODY_TYPE"PLUMBING"
HDL_TAP"TRUE";
"B \NAC \NWC"5;
"S \NAC"
BN"0"122;
%"TAP"
"1","(-3350,2650)","0","mstr_standard","I232";
;
CDS_LIB"mstr_standard"
BODY_TYPE"PLUMBING"
HDL_TAP"TRUE";
"B \NAC \NWC"5;
"S \NAC"
BN"1"126;
%"TAP"
"1","(-3350,2750)","0","mstr_standard","I233";
;
CDS_LIB"mstr_standard"
BODY_TYPE"PLUMBING"
HDL_TAP"TRUE";
"B \NAC \NWC"5;
"S \NAC"
BN"2"130;
%"TAP"
"1","(-3550,2700)","0","mstr_standard","I234";
;
CDS_LIB"mstr_standard"
BODY_TYPE"PLUMBING"
HDL_TAP"TRUE";
"B \NAC \NWC"4;
"S \NAC"
BN"1"127;
%"TAP"
"1","(-3550,2600)","0","mstr_standard","I235";
;
CDS_LIB"mstr_standard"
BODY_TYPE"PLUMBING"
HDL_TAP"TRUE";
"B \NAC \NWC"4;
"S \NAC"
BN"0"123;
%"SCONN288_DDR506112002KQ"
"2","(-4500,3550)","0","pure_quanta","I236";
;
LOCATION"J28"
$SEC"2"
CDS_SEC"2"
PART_TYPE"SMLF"
MATERIAL"IO"
VALUE"SCONN288_DDR506112002KQ"
CDS_LMAN_SYM_OUTLINE"-600,1150,600,-1150"
NEEDS_NO_SIZE"TRUE"
CDS_LIB"pure_quanta"
PART_NUMBER"DFHST8FS479";
"DQS7_A_C||TDQS7_A_C \B"
$PN"178"115;
"DQS6_A_T||TDQS6_A_T"
$PN"168"116;
"DQS8_B_T||TDQS8_B_T"
$PN"283"117;
"DQS8_B_C||TDQS8_B_C \B"
$PN"282"118;
"DQS7_B_T||TDQS7_B_T"
$PN"272"119;
"DQS0_A_C \B"
$PN"12"120;
"DQS0_A_T"
$PN"11"121;
"DQS0_B_C \B"
$PN"105"122;
"DQS0_B_T"
$PN"104"123;
"DQS1_A_C \B"
$PN"23"124;
"DQS1_A_T"
$PN"22"125;
"DQS1_B_C \B"
$PN"116"126;
"DQS1_B_T"
$PN"115"127;
"DQS2_A_C \B"
$PN"34"128;
"DQS2_A_T"
$PN"33"129;
"DQS2_B_C \B"
$PN"127"130;
"DQS2_B_T"
$PN"126"131;
"DQS3_A_C \B"
$PN"45"132;
"DQS3_A_T"
$PN"44"133;
"DQS3_B_C \B"
$PN"138"134;
"DQS3_B_T"
$PN"137"135;
"DQS4_A_C \B"
$PN"56"136;
"DQS4_A_T"
$PN"55"137;
"DQS4_B_C \B"
$PN"238"138;
"DQS4_B_T"
$PN"239"139;
"DQS5_A_C||TDQS5_A_C||DQS5_A_T||TDQS5_A_T \B"
$PN"156"140;
"DQS5_A_T||TDQS5_A_T"
$PN"157"141;
"DQS5_B_C||TDQS5_B_C \B"
$PN"249"142;
"DQS5_B_T||TDQS5_B_T"
$PN"250"143;
"DQS6_A_C||TDQS6_A_C||DQS6_A_T||TDQS6_A_T \B"
$PN"167"144;
"DQS6_B_C||TDQS6_B_C \B"
$PN"260"145;
"DQS6_B_T||TDQS6_B_T"
$PN"261"146;
"DQS7_A_T||TDQS7_A_T"
$PN"179"147;
"DQS7_B_C||TDQS7_B_C \B"
$PN"271"148;
"DQS8_A_C||TDQS8_A_C \B"
$PN"189"149;
"DQS8_A_T||TDQS8_A_T"
$PN"190"150;
"DQS9_A_C||TDQS9_A_C \B"
$PN"200"151;
"DQS9_A_T||TDQS9_A_T"
$PN"201"152;
"DQS9_B_C||TDQS9_B_C \B"
$PN"94"153;
"DQS9_B_T||TDQS9_B_T||DBI4_B_N"
$PN"93"154;
%"GND"
"1","(-2925,5525)","0","pure_quanta_power","I237";
;
CDS_LIB"pure_quanta_power"
BOM_COST"MEM"
SIZE"1B"
ROOM"MEM_EFGH_DECOUPLING_CAPS"
HDL_POWER"GND";
"A<SIZE-1..0>\NAC"162;
%"Q_CAP"
"1","(-2925,5875)","2","pure_quanta","I238";
;
LOCATION"C178"
$SEC"1"
CDS_SEC"1"
VOLTAGE"25V"
TOLERANCE"10%"
PACK_TYPE"C0805"
VALUE"10UF"
MATERIAL"X6S"
CDS_LIB"pure_quanta"
BOM_COST"MEM"
ROOM""
PART_NUMBER"CH6104KEA00";
"B"
$PN"2"162;
"A"
$PN"1"161;
%"Q_CAP"
"1","(-2350,5875)","2","pure_quanta","I239";
;
LOCATION"C179"
$SEC"1"
CDS_SEC"1"
MATERIAL"X6S"
PACK_TYPE"C0805"
VOLTAGE"25V"
VALUE"10UF"
TOLERANCE"10%"
CDS_LIB"pure_quanta"
BOM_COST"MEM"
ROOM""
PART_NUMBER"CH6104KEA00";
"B"
$PN"2"162;
"A"
$PN"1"161;
%"TAP"
"1","(-7900,3300)","2","mstr_standard","I24";
;
CDS_LIB"mstr_standard"
BODY_TYPE"PLUMBING"
HDL_TAP"TRUE";
"B \NAC \NWC"10;
"S \NAC"
BN"2"42;
%"UNIVERSAL_POWER"
"1","(-2925,6200)","0","pure_quanta_power","I240";
;
HDL_POWER"P12V_MEM_CPU1"
CDS_LIB"pure_quanta_power";
"A"161;
%"Q_RES"
"1","(-7925,2625)","0","pure_quanta","I242";
;
LOCATION"R1582"
$SEC"1"
CDS_SEC"1"
VALUE"49.9"
MATERIAL"CHIP"
PACK_TYPE"0402LF"
WATTAGE"1/16W"
TOLERANCE"1%"
CDS_LIB"pure_quanta"
PART_NUMBER"CS04992FB07";
"B"
$PN"2"171;
"A"
$PN"1"167;
%"Q_RES"
"1","(-8300,2850)","0","pure_quanta","I243";
;
LOCATION"R1697"
$SEC"1"
CDS_SEC"1"
VALUE"10"
PACK_TYPE"0402LF"
MATERIAL"CHIP"
CDS_LIB"pure_quanta"
WATTAGE"1/16W"
TOLERANCE"1%"
PART_NUMBER"CS01002FB07";
"B"
$PN"2"170;
"A"
$PN"1"168;
%"TAP"
"1","(-7900,3250)","2","mstr_standard","I25";
;
CDS_LIB"mstr_standard"
BODY_TYPE"PLUMBING"
HDL_TAP"TRUE";
"B \NAC \NWC"10;
"S \NAC"
BN"1"43;
%"TAP"
"1","(-7900,3350)","2","mstr_standard","I26";
;
CDS_LIB"mstr_standard"
BODY_TYPE"PLUMBING"
HDL_TAP"TRUE";
"B \NAC \NWC"10;
"S \NAC"
BN"3"41;
%"TAP"
"1","(-7900,3400)","2","mstr_standard","I27";
;
CDS_LIB"mstr_standard"
BODY_TYPE"PLUMBING"
HDL_TAP"TRUE";
"B \NAC \NWC"10;
"S \NAC"
BN"4"40;
%"TAP"
"1","(-7900,3450)","2","mstr_standard","I28";
;
CDS_LIB"mstr_standard"
BODY_TYPE"PLUMBING"
HDL_TAP"TRUE";
"B \NAC \NWC"10;
"S \NAC"
BN"5"39;
%"TAP"
"1","(-7900,3550)","2","mstr_standard","I29";
;
CDS_LIB"mstr_standard"
BODY_TYPE"PLUMBING"
HDL_TAP"TRUE";
"B \NAC \NWC"10;
"S \NAC"
BN"7"18;
%"TAP"
"1","(-7900,3500)","2","mstr_standard","I30";
;
CDS_LIB"mstr_standard"
BODY_TYPE"PLUMBING"
HDL_TAP"TRUE";
"B \NAC \NWC"10;
"S \NAC"
BN"6"38;
%"TAP"
"1","(-7900,3650)","2","mstr_standard","I31";
;
CDS_LIB"mstr_standard"
BODY_TYPE"PLUMBING"
HDL_TAP"TRUE";
"B \NAC \NWC"11;
"S \NAC"
BN"0"37;
%"TAP"
"1","(-7900,3700)","2","mstr_standard","I32";
;
CDS_LIB"mstr_standard"
BODY_TYPE"PLUMBING"
HDL_TAP"TRUE";
"B \NAC \NWC"11;
"S \NAC"
BN"1"17;
%"TAP"
"1","(-7900,3750)","2","mstr_standard","I33";
;
CDS_LIB"mstr_standard"
BODY_TYPE"PLUMBING"
HDL_TAP"TRUE";
"B \NAC \NWC"11;
"S \NAC"
BN"2"36;
%"TAP"
"1","(-7900,3800)","2","mstr_standard","I34";
;
CDS_LIB"mstr_standard"
BODY_TYPE"PLUMBING"
HDL_TAP"TRUE";
"B \NAC \NWC"11;
"S \NAC"
BN"3"35;
%"TAP"
"1","(-6200,2250)","0","mstr_standard","I35";
;
CDS_LIB"mstr_standard"
BODY_TYPE"PLUMBING"
HDL_TAP"TRUE";
"B \NAC \NWC"8;
"S \NAC"
BN"1"110;
%"TAP"
"1","(-6200,2200)","0","mstr_standard","I36";
;
CDS_LIB"mstr_standard"
BODY_TYPE"PLUMBING"
HDL_TAP"TRUE";
"B \NAC \NWC"8;
"S \NAC"
BN"0"111;
%"TAP"
"1","(-6200,2300)","0","mstr_standard","I37";
;
CDS_LIB"mstr_standard"
BODY_TYPE"PLUMBING"
HDL_TAP"TRUE";
"B \NAC \NWC"8;
"S \NAC"
BN"2"109;
%"TAP"
"1","(-6200,2350)","0","mstr_standard","I38";
;
CDS_LIB"mstr_standard"
BODY_TYPE"PLUMBING"
HDL_TAP"TRUE";
"B \NAC \NWC"8;
"S \NAC"
BN"3"108;
%"TAP"
"1","(-6200,2400)","0","mstr_standard","I39";
;
CDS_LIB"mstr_standard"
BODY_TYPE"PLUMBING"
HDL_TAP"TRUE";
"B \NAC \NWC"8;
"S \NAC"
BN"4"107;
%"TAP"
"1","(-6200,2450)","0","mstr_standard","I40";
;
CDS_LIB"mstr_standard"
BODY_TYPE"PLUMBING"
HDL_TAP"TRUE";
"B \NAC \NWC"8;
"S \NAC"
BN"5"106;
%"TAP"
"1","(-6200,2550)","0","mstr_standard","I41";
;
CDS_LIB"mstr_standard"
BODY_TYPE"PLUMBING"
HDL_TAP"TRUE";
"B \NAC \NWC"8;
"S \NAC"
BN"7"104;
%"TAP"
"1","(-6200,2500)","0","mstr_standard","I42";
;
CDS_LIB"mstr_standard"
BODY_TYPE"PLUMBING"
HDL_TAP"TRUE";
"B \NAC \NWC"8;
"S \NAC"
BN"6"105;
%"TAP"
"1","(-6200,2650)","0","mstr_standard","I43";
;
CDS_LIB"mstr_standard"
BODY_TYPE"PLUMBING"
HDL_TAP"TRUE";
"B \NAC \NWC"8;
"S \NAC"
BN"9"102;
%"TAP"
"1","(-6200,2600)","0","mstr_standard","I44";
;
CDS_LIB"mstr_standard"
BODY_TYPE"PLUMBING"
HDL_TAP"TRUE";
"B \NAC \NWC"8;
"S \NAC"
BN"8"103;
%"TAP"
"1","(-6200,2750)","0","mstr_standard","I45";
;
CDS_LIB"mstr_standard"
BODY_TYPE"PLUMBING"
HDL_TAP"TRUE";
"B \NAC \NWC"8;
"S \NAC"
BN"11"100;
%"TAP"
"1","(-6200,2800)","0","mstr_standard","I46";
;
CDS_LIB"mstr_standard"
BODY_TYPE"PLUMBING"
HDL_TAP"TRUE";
"B \NAC \NWC"8;
"S \NAC"
BN"12"99;
%"TAP"
"1","(-6200,2700)","0","mstr_standard","I47";
;
CDS_LIB"mstr_standard"
BODY_TYPE"PLUMBING"
HDL_TAP"TRUE";
"B \NAC \NWC"8;
"S \NAC"
BN"10"101;
%"TAP"
"1","(-6200,2850)","0","mstr_standard","I48";
;
CDS_LIB"mstr_standard"
BODY_TYPE"PLUMBING"
HDL_TAP"TRUE";
"B \NAC \NWC"8;
"S \NAC"
BN"13"98;
%"TAP"
"1","(-6200,2900)","0","mstr_standard","I49";
;
CDS_LIB"mstr_standard"
BODY_TYPE"PLUMBING"
HDL_TAP"TRUE";
"B \NAC \NWC"8;
"S \NAC"
BN"14"97;
%"TAP"
"1","(-6200,2950)","0","mstr_standard","I50";
;
CDS_LIB"mstr_standard"
BODY_TYPE"PLUMBING"
HDL_TAP"TRUE";
"B \NAC \NWC"8;
"S \NAC"
BN"15"96;
%"TAP"
"1","(-6200,3050)","0","mstr_standard","I51";
;
CDS_LIB"mstr_standard"
BODY_TYPE"PLUMBING"
HDL_TAP"TRUE";
"B \NAC \NWC"8;
"S \NAC"
BN"17"94;
%"TAP"
"1","(-6200,3000)","0","mstr_standard","I52";
;
CDS_LIB"mstr_standard"
BODY_TYPE"PLUMBING"
HDL_TAP"TRUE";
"B \NAC \NWC"8;
"S \NAC"
BN"16"95;
%"TAP"
"1","(-6200,3100)","0","mstr_standard","I53";
;
CDS_LIB"mstr_standard"
BODY_TYPE"PLUMBING"
HDL_TAP"TRUE";
"B \NAC \NWC"8;
"S \NAC"
BN"18"93;
%"TAP"
"1","(-6200,3150)","0","mstr_standard","I54";
;
CDS_LIB"mstr_standard"
BODY_TYPE"PLUMBING"
HDL_TAP"TRUE";
"B \NAC \NWC"8;
"S \NAC"
BN"19"92;
%"TAP"
"1","(-6200,3200)","0","mstr_standard","I55";
;
CDS_LIB"mstr_standard"
BODY_TYPE"PLUMBING"
HDL_TAP"TRUE";
"B \NAC \NWC"8;
"S \NAC"
BN"20"91;
%"TAP"
"1","(-6200,3300)","0","mstr_standard","I56";
;
CDS_LIB"mstr_standard"
BODY_TYPE"PLUMBING"
HDL_TAP"TRUE";
"B \NAC \NWC"8;
"S \NAC"
BN"22"89;
%"TAP"
"1","(-6200,3250)","0","mstr_standard","I57";
;
CDS_LIB"mstr_standard"
BODY_TYPE"PLUMBING"
HDL_TAP"TRUE";
"B \NAC \NWC"8;
"S \NAC"
BN"21"90;
%"TAP"
"1","(-6200,3350)","0","mstr_standard","I58";
;
CDS_LIB"mstr_standard"
BODY_TYPE"PLUMBING"
HDL_TAP"TRUE";
"B \NAC \NWC"8;
"S \NAC"
BN"23"88;
%"TAP"
"1","(-6200,3450)","0","mstr_standard","I59";
;
CDS_LIB"mstr_standard"
BODY_TYPE"PLUMBING"
HDL_TAP"TRUE";
"B \NAC \NWC"8;
"S \NAC"
BN"25"86;
%"VCC_CORE"
"1","(-8675,3425)","0","mstr_symbols","I6";
;
HDL_POWER"P3V3_AUX"
CDS_LIB"mstr_symbols"
VOLTAGE"3.3"
ROOM"PVCCINFAON_CPU1_CTRL";
"A"169;
%"TAP"
"1","(-6200,3400)","0","mstr_standard","I60";
;
CDS_LIB"mstr_standard"
BODY_TYPE"PLUMBING"
HDL_TAP"TRUE";
"B \NAC \NWC"8;
"S \NAC"
BN"24"87;
%"TAP"
"1","(-6200,3500)","0","mstr_standard","I61";
;
CDS_LIB"mstr_standard"
BODY_TYPE"PLUMBING"
HDL_TAP"TRUE";
"B \NAC \NWC"8;
"S \NAC"
BN"26"85;
%"TAP"
"1","(-6200,3550)","0","mstr_standard","I62";
;
CDS_LIB"mstr_standard"
BODY_TYPE"PLUMBING"
HDL_TAP"TRUE";
"B \NAC \NWC"8;
"S \NAC"
BN"27"84;
%"TAP"
"1","(-6200,3650)","0","mstr_standard","I63";
;
CDS_LIB"mstr_standard"
BODY_TYPE"PLUMBING"
HDL_TAP"TRUE";
"B \NAC \NWC"8;
"S \NAC"
BN"29"82;
%"TAP"
"1","(-6200,3700)","0","mstr_standard","I64";
;
CDS_LIB"mstr_standard"
BODY_TYPE"PLUMBING"
HDL_TAP"TRUE";
"B \NAC \NWC"8;
"S \NAC"
BN"30"81;
%"TAP"
"1","(-6200,3600)","0","mstr_standard","I65";
;
CDS_LIB"mstr_standard"
BODY_TYPE"PLUMBING"
HDL_TAP"TRUE";
"B \NAC \NWC"8;
"S \NAC"
BN"28"83;
%"TAP"
"1","(-6200,3750)","0","mstr_standard","I66";
;
CDS_LIB"mstr_standard"
BODY_TYPE"PLUMBING"
HDL_TAP"TRUE";
"B \NAC \NWC"8;
"S \NAC"
BN"31"80;
%"TAP"
"1","(-7900,3850)","2","mstr_standard","I79";
;
CDS_LIB"mstr_standard"
BODY_TYPE"PLUMBING"
HDL_TAP"TRUE";
"B \NAC \NWC"11;
"S \NAC"
BN"4"16;
%"TAP"
"1","(-7900,3900)","2","mstr_standard","I80";
;
CDS_LIB"mstr_standard"
BODY_TYPE"PLUMBING"
HDL_TAP"TRUE";
"B \NAC \NWC"11;
"S \NAC"
BN"5"34;
%"TAP"
"1","(-7900,3950)","2","mstr_standard","I81";
;
CDS_LIB"mstr_standard"
BODY_TYPE"PLUMBING"
HDL_TAP"TRUE";
"B \NAC \NWC"11;
"S \NAC"
BN"6"33;
%"TAP"
"1","(-7900,4000)","2","mstr_standard","I82";
;
CDS_LIB"mstr_standard"
BODY_TYPE"PLUMBING"
HDL_TAP"TRUE";
"B \NAC \NWC"11;
"S \NAC"
BN"7"15;
%"TAP"
"1","(-7900,4700)","2","mstr_standard","I83";
;
CDS_LIB"mstr_standard"
BODY_TYPE"PLUMBING"
HDL_TAP"TRUE";
"B \NAC \NWC"12;
"S \NAC"
BN"0"20;
%"TAP"
"1","(-7900,4800)","2","mstr_standard","I84";
;
CDS_LIB"mstr_standard"
BODY_TYPE"PLUMBING"
HDL_TAP"TRUE";
"B \NAC \NWC"12;
"S \NAC"
BN"2"24;
%"TAP"
"1","(-7900,4750)","2","mstr_standard","I85";
;
CDS_LIB"mstr_standard"
BODY_TYPE"PLUMBING"
HDL_TAP"TRUE";
"B \NAC \NWC"12;
"S \NAC"
BN"1"22;
%"TAP"
"1","(-7900,4850)","2","mstr_standard","I86";
;
CDS_LIB"mstr_standard"
BODY_TYPE"PLUMBING"
HDL_TAP"TRUE";
"B \NAC \NWC"12;
"S \NAC"
BN"3"26;
%"TAP"
"1","(-7900,4900)","2","mstr_standard","I87";
;
CDS_LIB"mstr_standard"
BODY_TYPE"PLUMBING"
HDL_TAP"TRUE";
"B \NAC \NWC"12;
"S \NAC"
BN"4"28;
%"TAP"
"1","(-7900,4950)","2","mstr_standard","I88";
;
CDS_LIB"mstr_standard"
BODY_TYPE"PLUMBING"
HDL_TAP"TRUE";
"B \NAC \NWC"12;
"S \NAC"
BN"5"30;
%"TAP"
"1","(-7900,5000)","2","mstr_standard","I89";
;
CDS_LIB"mstr_standard"
BODY_TYPE"PLUMBING"
HDL_TAP"TRUE";
"B \NAC \NWC"12;
"S \NAC"
BN"6"32;
%"TAP"
"1","(-7900,5100)","2","mstr_standard","I90";
;
CDS_LIB"mstr_standard"
BODY_TYPE"PLUMBING"
HDL_TAP"TRUE";
"B \NAC \NWC"13;
"S \NAC"
BN"0"19;
%"TAP"
"1","(-7900,5150)","2","mstr_standard","I91";
;
CDS_LIB"mstr_standard"
BODY_TYPE"PLUMBING"
HDL_TAP"TRUE";
"B \NAC \NWC"13;
"S \NAC"
BN"1"21;
%"TAP"
"1","(-7900,5200)","2","mstr_standard","I92";
;
CDS_LIB"mstr_standard"
BODY_TYPE"PLUMBING"
HDL_TAP"TRUE";
"B \NAC \NWC"13;
"S \NAC"
BN"2"23;
%"TAP"
"1","(-7900,5250)","2","mstr_standard","I93";
;
CDS_LIB"mstr_standard"
BODY_TYPE"PLUMBING"
HDL_TAP"TRUE";
"B \NAC \NWC"13;
"S \NAC"
BN"3"25;
%"TAP"
"1","(-7900,5350)","2","mstr_standard","I94";
;
CDS_LIB"mstr_standard"
BODY_TYPE"PLUMBING"
HDL_TAP"TRUE";
"B \NAC \NWC"13;
"S \NAC"
BN"5"29;
%"TAP"
"1","(-7900,5300)","2","mstr_standard","I95";
;
CDS_LIB"mstr_standard"
BODY_TYPE"PLUMBING"
HDL_TAP"TRUE";
"B \NAC \NWC"13;
"S \NAC"
BN"4"27;
%"TAP"
"1","(-7900,5400)","2","mstr_standard","I96";
;
CDS_LIB"mstr_standard"
BODY_TYPE"PLUMBING"
HDL_TAP"TRUE";
"B \NAC \NWC"13;
"S \NAC"
BN"6"31;
%"TAP"
"1","(-6200,3850)","0","mstr_standard","I97";
;
CDS_LIB"mstr_standard"
BODY_TYPE"PLUMBING"
HDL_TAP"TRUE";
"B \NAC \NWC"9;
"S \NAC"
BN"0"79;
%"TAP"
"1","(-6200,3950)","0","mstr_standard","I98";
;
CDS_LIB"mstr_standard"
BODY_TYPE"PLUMBING"
HDL_TAP"TRUE";
"B \NAC \NWC"9;
"S \NAC"
BN"2"77;
%"TAP"
"1","(-6200,3900)","0","mstr_standard","I99";
;
CDS_LIB"mstr_standard"
BODY_TYPE"PLUMBING"
HDL_TAP"TRUE";
"B \NAC \NWC"9;
"S \NAC"
BN"1"78;
END.
